# T6G (Grand Teton) — schematic netlist excerpt (pin names and nets, part order shuffled) for the footprints in the layout excerpt that follows; sources: Cadence DE-HDL packaged netlist, KiCad conversion of 04192023_DAF0TMB3IC0_F0TG_MB_C_brd_V02_OCP.brd

R4013  Q_RES  100K 1% CHIP  pkg 0402LF  page 152 : A = P3V3_AUX ; B = P12V_SCM_FAULT_R_N
PR3792  Q_RES  10 1% CHIP  pkg 0402LF  page 134 : A = P12V_AUX ; B = P12V_OCP_VCC_1

(kicad_pcb
	(version 20260206)
	(generator "pcbnew")
	(generator_version "10.0")
	(general
		(thickness 1.6)
		(legacy_teardrops no)
	)
	(paper "A4")
	(title_block
		(title "04192023_DAF0TMB3IC0_F0TG_MB_C_brd_V02_OCP.brd")
		(comment 1 "Grand Teton / footprints 3347-3348 of 8354")
	)
	(layers
		(0 "F.Cu" signal "TOP")
		(4 "In1.Cu" signal "GND")
		(6 "In2.Cu" signal "IN1")
		(8 "In3.Cu" signal "GND1")
		(10 "In4.Cu" signal "IN2")
		(12 "In5.Cu" signal "GND2")
		(14 "In6.Cu" signal "IN3")
		(16 "In7.Cu" signal "GND3")
		(18 "In8.Cu" signal "VCC")
		(20 "In9.Cu" signal "VCC1")
		(22 "In10.Cu" signal "GND4")
		(24 "In11.Cu" signal "IN4")
		(26 "In12.Cu" signal "GND5")
		(28 "In13.Cu" signal "IN5")
		(30 "In14.Cu" signal "GND6")
		(32 "In15.Cu" signal "IN6")
		(34 "In16.Cu" signal "GND7")
		(2 "B.Cu" signal "BOTTOM")
		(9 "F.Adhes" user "F.Adhesive")
		(11 "B.Adhes" user "B.Adhesive")
		(13 "F.Paste" user "Package Geometry/Pastemask Top")
		(15 "B.Paste" user "Package Geometry/Pastemask Bottom")
		(5 "F.SilkS" user "Ref Des/Silkscreen Top")
		(7 "B.SilkS" user "Ref Des/Silkscreen Bottom")
		(1 "F.Mask" user "Board Geometry/Soldermask Top")
		(3 "B.Mask" user "Board Geometry/Soldermask Bottom")
		(17 "Dwgs.User" user "User.Drawings")
		(19 "Cmts.User" user "User.Comments")
		(21 "Eco1.User" user "User.Eco1")
		(23 "Eco2.User" user "User.Eco2")
		(25 "Edge.Cuts" user "Board Geometry/Outline")
		(27 "Margin" user)
		(31 "F.CrtYd" user "Package Geometry/Place Bound Top")
		(29 "B.CrtYd" user "Package Geometry/Place Bound Bottom")
		(35 "F.Fab" user "Ref Des/Assembly Top")
		(33 "B.Fab" user "Ref Des/Assembly Bottom")
	)
	(footprint ""
		(layer "F.Cu")
		(at 450.060314 -25.10028 -90)
		(property "Reference" "PR3792"
			(at 0 0 270)
			(layer "F.SilkS")
			(hide yes)
			(effects
				(font
					(size 1.27 1.27)
				)
			)
		)
		(property "Value" ""
			(at 0 0 270)
			(layer "F.Fab")
			(effects
				(font
					(size 1.27 1.27)
				)
			)
		)
		(duplicate_pad_numbers_are_jumpers no)
		(fp_line
			(start -0.7874 0.4064)
			(end -0.7874 -0.4064)
			(stroke
				(width 0.1524)
				(type default)
			)
			(layer "F.SilkS")
		)
		(fp_line
			(start 0.7874 0.4064)
			(end -0.7874 0.4064)
			(stroke
				(width 0.1524)
				(type default)
			)
			(layer "F.SilkS")
		)
		(fp_line
			(start -0.7874 -0.4064)
			(end 0.7874 -0.4064)
			(stroke
				(width 0.1524)
				(type default)
			)
			(layer "F.SilkS")
		)
		(fp_line
			(start 0.7874 -0.4064)
			(end 0.7874 0.4064)
			(stroke
				(width 0.1524)
				(type default)
			)
			(layer "F.SilkS")
		)
		(fp_line
			(start -0.67945 0.3048)
			(end -0.67945 -0.305054)
			(stroke
				(width 0.1)
				(type default)
			)
			(layer "F.Fab")
		)
		(fp_line
			(start -0.12065 0.3048)
			(end -0.67945 0.3048)
			(stroke
				(width 0.1)
				(type default)
			)
			(layer "F.Fab")
		)
		(fp_line
			(start 0.120396 0.3048)
			(end 0.120396 0.2794)
			(stroke
				(width 0.1)
				(type default)
			)
			(layer "F.Fab")
		)
		(fp_line
			(start 0.67945 0.3048)
			(end 0.120396 0.3048)
			(stroke
				(width 0.1)
				(type default)
			)
			(layer "F.Fab")
		)
		(fp_line
			(start -0.12065 0.2794)
			(end -0.12065 0.3048)
			(stroke
				(width 0.1)
				(type default)
			)
			(layer "F.Fab")
		)
		(fp_line
			(start 0.120396 0.2794)
			(end -0.12065 0.2794)
			(stroke
				(width 0.1)
				(type default)
			)
			(layer "F.Fab")
		)
		(fp_line
			(start -0.12065 -0.2794)
			(end 0.12065 -0.2794)
			(stroke
				(width 0.1)
				(type default)
			)
			(layer "F.Fab")
		)
		(fp_line
			(start 0.12065 -0.2794)
			(end 0.12065 -0.3048)
			(stroke
				(width 0.1)
				(type default)
			)
			(layer "F.Fab")
		)
		(fp_line
			(start 0.12065 -0.3048)
			(end 0.67945 -0.3048)
			(stroke
				(width 0.1)
				(type default)
			)
			(layer "F.Fab")
		)
		(fp_line
			(start 0.67945 -0.3048)
			(end 0.67945 0.3048)
			(stroke
				(width 0.1)
				(type default)
			)
			(layer "F.Fab")
		)
		(fp_line
			(start -0.67945 -0.305054)
			(end -0.12065 -0.305054)
			(stroke
				(width 0.1)
				(type default)
			)
			(layer "F.Fab")
		)
		(fp_line
			(start -0.12065 -0.305054)
			(end -0.12065 -0.2794)
			(stroke
				(width 0.1)
				(type default)
			)
			(layer "F.Fab")
		)
		(pad "1" smd circle
			(at -0.40005 0 270)
			(size 0 0)
			(layers "F.Cu" "F.Mask" "F.Paste")
			(net "P12V_AUX")
		)
		(pad "2" smd circle
			(at 0.40005 0 270)
			(size 0 0)
			(layers "F.Cu" "F.Mask" "F.Paste")
			(net "P12V_OCP_VCC_1")
		)
	)
	(footprint ""
		(layer "F.Cu")
		(at 193.089022 -25.965912 90)
		(property "Reference" "R4013"
			(at 0 0 90)
			(layer "F.SilkS")
			(hide yes)
			(effects
				(font
					(size 1.27 1.27)
				)
			)
		)
		(property "Value" ""
			(at 0 0 90)
			(layer "F.Fab")
			(effects
				(font
					(size 1.27 1.27)
				)
			)
		)
		(duplicate_pad_numbers_are_jumpers no)
		(fp_line
			(start 0.7874 -0.4064)
			(end 0.7874 0.4064)
			(stroke
				(width 0.1524)
				(type default)
			)
			(layer "F.SilkS")
		)
		(fp_line
			(start -0.7874 -0.4064)
			(end 0.7874 -0.4064)
			(stroke
				(width 0.1524)
				(type default)
			)
			(layer "F.SilkS")
		)
		(fp_line
			(start 0.7874 0.4064)
			(end -0.7874 0.4064)
			(stroke
				(width 0.1524)
				(type default)
			)
			(layer "F.SilkS")
		)
		(fp_line
			(start -0.7874 0.4064)
			(end -0.7874 -0.4064)
			(stroke
				(width 0.1524)
				(type default)
			)
			(layer "F.SilkS")
		)
		(fp_line
			(start -0.12065 -0.305054)
			(end -0.12065 -0.2794)
			(stroke
				(width 0.1)
				(type default)
			)
			(layer "F.Fab")
		)
		(fp_line
			(start -0.67945 -0.305054)
			(end -0.12065 -0.305054)
			(stroke
				(width 0.1)
				(type default)
			)
			(layer "F.Fab")
		)
		(fp_line
			(start 0.67945 -0.3048)
			(end 0.67945 0.3048)
			(stroke
				(width 0.1)
				(type default)
			)
			(layer "F.Fab")
		)
		(fp_line
			(start 0.12065 -0.3048)
			(end 0.67945 -0.3048)
			(stroke
				(width 0.1)
				(type default)
			)
			(layer "F.Fab")
		)
		(fp_line
			(start 0.12065 -0.2794)
			(end 0.12065 -0.3048)
			(stroke
				(width 0.1)
				(type default)
			)
			(layer "F.Fab")
		)
		(fp_line
			(start -0.12065 -0.2794)
			(end 0.12065 -0.2794)
			(stroke
				(width 0.1)
				(type default)
			)
			(layer "F.Fab")
		)
		(fp_line
			(start 0.120396 0.2794)
			(end -0.12065 0.2794)
			(stroke
				(width 0.1)
				(type default)
			)
			(layer "F.Fab")
		)
		(fp_line
			(start -0.12065 0.2794)
			(end -0.12065 0.3048)
			(stroke
				(width 0.1)
				(type default)
			)
			(layer "F.Fab")
		)
		(fp_line
			(start 0.67945 0.3048)
			(end 0.120396 0.3048)
			(stroke
				(width 0.1)
				(type default)
			)
			(layer "F.Fab")
		)
		(fp_line
			(start 0.120396 0.3048)
			(end 0.120396 0.2794)
			(stroke
				(width 0.1)
				(type default)
			)
			(layer "F.Fab")
		)
		(fp_line
			(start -0.12065 0.3048)
			(end -0.67945 0.3048)
			(stroke
				(width 0.1)
				(type default)
			)
			(layer "F.Fab")
		)
		(fp_line
			(start -0.67945 0.3048)
			(end -0.67945 -0.305054)
			(stroke
				(width 0.1)
				(type default)
			)
			(layer "F.Fab")
		)
		(pad "1" smd circle
			(at -0.40005 0 90)
			(size 0 0)
			(layers "F.Cu" "F.Mask" "F.Paste")
			(net "P3V3_AUX")
		)
		(pad "2" smd circle
			(at 0.40005 0 90)
			(size 0 0)
			(layers "F.Cu" "F.Mask" "F.Paste")
			(net "P12V_SCM_FAULT_R_N")
		)
	)
)
